(kicad_pcb
	(version 20260206)
	(generator "pcbnew")
	(generator_version "10.0")
	(general
		(thickness 1.6)
		(legacy_teardrops no)
	)
	(paper "A4")
	(title_block
		(title "Bryce Canyon_F.DPB_16315-1-OCP.brd")
		(comment 1 "Bryce Canyon / footprints 1839-1841 of 2223")
	)
	(layers
		(0 "F.Cu" signal "TOP")
		(4 "In1.Cu" signal "L2GND")
		(6 "In2.Cu" signal "L3")
		(8 "In3.Cu" signal "L4GND")
		(10 "In4.Cu" signal "L5")
		(12 "In5.Cu" signal "L6VCC")
		(14 "In6.Cu" signal "L7VCC")
		(16 "In7.Cu" signal "L8")
		(18 "In8.Cu" signal "L9GND")
		(20 "In9.Cu" signal "L10")
		(22 "In10.Cu" signal "L11GND")
		(2 "B.Cu" signal "BOTTOM")
		(9 "F.Adhes" user "F.Adhesive")
		(11 "B.Adhes" user "B.Adhesive")
		(13 "F.Paste" user "Package Geometry/Pastemask Top")
		(15 "B.Paste" user "Package Geometry/Pastemask Bottom")
		(5 "F.SilkS" user "Ref Des/Silkscreen Top")
		(7 "B.SilkS" user "Ref Des/Silkscreen Bottom")
		(1 "F.Mask" user "Board Geometry/Soldermask Top")
		(3 "B.Mask" user "Board Geometry/Soldermask Bottom")
		(17 "Dwgs.User" user "User.Drawings")
		(19 "Cmts.User" user "User.Comments")
		(21 "Eco1.User" user "User.Eco1")
		(23 "Eco2.User" user "User.Eco2")
		(25 "Edge.Cuts" user "Board Geometry/Outline")
		(27 "Margin" user)
		(31 "F.CrtYd" user "Package Geometry/Place Bound Top")
		(29 "B.CrtYd" user "Package Geometry/Place Bound Bottom")
		(35 "F.Fab" user "Ref Des/Assembly Top")
		(33 "B.Fab" user "Ref Des/Assembly Bottom")
	)
	(footprint ""
		(layer "F.Cu")
		(at 445.5922 -256.35712 180)
		(property "Reference" "R1261"
			(at 0 0 180)
			(layer "F.SilkS")
			(hide yes)
			(effects
				(font
					(size 1.27 1.27)
				)
			)
		)
		(property "Value" "0R2J-2-GP"
			(at 0.064008 -3.993896 180)
			(unlocked yes)
			(layer "F.Fab")
			(hide yes)
			(effects
				(font
					(size 1.016 1.016)
					(thickness 0.1524)
				)
			)
		)
		(property "Device Type" "R402H16"
			(at 0.064008 -5.517896 180)
			(unlocked yes)
			(layer "F.Fab")
			(hide yes)
			(effects
				(font
					(size 1.016 1.016)
					(thickness 0.1524)
				)
			)
		)
		(duplicate_pad_numbers_are_jumpers no)
		(fp_line
			(start 0.508 -0.9398)
			(end -0.508 -0.9398)
			(stroke
				(width 0.1524)
				(type default)
			)
			(layer "F.SilkS")
		)
		(fp_line
			(start -0.508 -0.9398)
			(end -0.508 0.9398)
			(stroke
				(width 0.1524)
				(type default)
			)
			(layer "F.SilkS")
		)
		(fp_rect
			(start -0.508 0.9398)
			(end 0.508 -0.9398)
			(stroke
				(width 0)
				(type default)
			)
			(fill no)
			(layer "F.CrtYd")
		)
		(fp_rect
			(start -0.508 0.9398)
			(end 0.508 -0.9398)
			(stroke
				(width 0)
				(type default)
			)
			(fill no)
			(layer "F.Fab")
		)
		(pad "1" smd custom
			(at 0 -0.4445 180)
			(size 0.1397 0.1397)
			(layers "F.Cu" "F.Mask" "F.Paste")
			(net "P5V_C_ROVP")
			(options
				(clearance outline)
				(anchor circle)
			)
			(primitives
				(gr_poly
					(pts
						(arc
							(start -0.1778 -0.2794)
							(mid -0.249642 -0.249642)
							(end -0.2794 -0.1778)
						)
						(arc
							(start -0.2794 0.1778)
							(mid -0.249642 0.249642)
							(end -0.1778 0.2794)
						)
						(arc
							(start 0.1778 0.2794)
							(mid 0.249642 0.249642)
							(end 0.2794 0.1778)
						)
						(arc
							(start 0.2794 -0.1778)
							(mid 0.249642 -0.249642)
							(end 0.1778 -0.2794)
						)
					)
					(width 0)
					(fill yes)
				)
			)
		)
		(pad "2" smd custom
			(at 0 0.4445 180)
			(size 0.1397 0.1397)
			(layers "F.Cu" "F.Mask" "F.Paste")
			(net "AGND_P5V_C")
			(options
				(clearance outline)
				(anchor circle)
			)
			(primitives
				(gr_poly
					(pts
						(arc
							(start -0.1778 -0.2794)
							(mid -0.249642 -0.249642)
							(end -0.2794 -0.1778)
						)
						(arc
							(start -0.2794 0.1778)
							(mid -0.249642 0.249642)
							(end -0.1778 0.2794)
						)
						(arc
							(start 0.1778 0.2794)
							(mid 0.249642 0.249642)
							(end 0.2794 0.1778)
						)
						(arc
							(start 0.2794 -0.1778)
							(mid 0.249642 -0.249642)
							(end 0.1778 -0.2794)
						)
					)
					(width 0)
					(fill yes)
				)
			)
		)
	)
	(footprint ""
		(layer "F.Cu")
		(at 109.492796 -59.857894)
		(property "Reference" "Q164"
			(at 0 0 0)
			(layer "F.SilkS")
			(hide yes)
			(effects
				(font
					(size 1.27 1.27)
				)
			)
		)
		(property "Value" "AO4407AL-GP"
			(at -3.707384 -1.5367 0)
			(unlocked yes)
			(layer "F.Fab")
			(hide yes)
			(effects
				(font
					(size 1.016 1.016)
					(thickness 0.1524)
				)
			)
		)
		(property "Device Type" "SOIC8H69"
			(at -3.707384 -3.0607 0)
			(unlocked yes)
			(layer "F.Fab")
			(hide yes)
			(effects
				(font
					(size 1.016 1.016)
					(thickness 0.1524)
				)
			)
		)
		(duplicate_pad_numbers_are_jumpers no)
		(fp_line
			(start -2.7432 -1.4224)
			(end -2.7432 1.4224)
			(stroke
				(width 0.1524)
				(type default)
			)
			(layer "F.SilkS")
		)
		(fp_line
			(start -2.7432 1.4224)
			(end -2.6416 1.4224)
			(stroke
				(width 0.1524)
				(type default)
			)
			(layer "F.SilkS")
		)
		(fp_line
			(start -2.7432 1.4224)
			(end 2.1336 1.4224)
			(stroke
				(width 0.1524)
				(type default)
			)
			(layer "F.SilkS")
		)
		(fp_line
			(start -2.7178 -0.508)
			(end -2.1844 -0.0508)
			(stroke
				(width 0.1524)
				(type default)
			)
			(layer "F.SilkS")
		)
		(fp_line
			(start -2.6289 3.4417)
			(end -2.6289 1.4732)
			(stroke
				(width 0.381)
				(type default)
			)
			(layer "F.SilkS")
		)
		(fp_line
			(start -2.1844 -0.0508)
			(end -2.7178 0.508)
			(stroke
				(width 0.1524)
				(type default)
			)
			(layer "F.SilkS")
		)
		(fp_line
			(start 2.1336 -1.4224)
			(end -2.7432 -1.4224)
			(stroke
				(width 0.1524)
				(type default)
			)
			(layer "F.SilkS")
		)
		(fp_line
			(start 2.1336 1.4224)
			(end 2.1336 -1.4224)
			(stroke
				(width 0.1524)
				(type default)
			)
			(layer "F.SilkS")
		)
		(fp_poly
			(pts
				(xy -2.2098 -1.4224) (xy -2.2098 1.4224) (xy 2.2098 1.4224) (xy 2.2098 -1.4224)
			)
			(stroke
				(width 0)
				(type default)
			)
			(fill yes)
			(layer "F.SilkS")
		)
		(fp_rect
			(start -2.450084 2.999994)
			(end 2.450084 -2.999994)
			(stroke
				(width 0)
				(type default)
			)
			(fill no)
			(layer "F.CrtYd")
		)
		(fp_poly
			(pts
				(xy -2.8194 3.6322) (xy -2.8194 -3.6322) (xy 2.8194 -3.6322) (xy 2.8194 1.18364) (xy 2.450084 1.18364)
				(xy 2.450084 -2.999994) (xy -2.450084 -2.999994) (xy -2.450084 2.999994) (xy 2.450084 2.999994)
				(xy 2.450084 1.18618) (xy 2.8194 1.18618) (xy 2.8194 3.6322)
			)
			(stroke
				(width 0)
				(type default)
			)
			(fill no)
			(layer "F.CrtYd")
		)
		(fp_rect
			(start -2.8194 3.6322)
			(end 2.8194 -3.6322)
			(stroke
				(width 0)
				(type default)
			)
			(fill no)
			(layer "F.Fab")
		)
		(pad "1" smd rect
			(at -1.905 2.54)
			(size 0.635 1.651)
			(layers "F.Cu" "F.Mask" "F.Paste")
			(net "P12V_A")
		)
		(pad "2" smd rect
			(at -0.635 2.54)
			(size 0.635 1.651)
			(layers "F.Cu" "F.Mask" "F.Paste")
			(net "P12V_A")
		)
		(pad "3" smd rect
			(at 0.635 2.54)
			(size 0.635 1.651)
			(layers "F.Cu" "F.Mask" "F.Paste")
			(net "P12V_A")
		)
		(pad "4" smd rect
			(at 1.905 2.54)
			(size 0.635 1.651)
			(layers "F.Cu" "F.Mask" "F.Paste")
			(net "SW_HDD_N27")
		)
		(pad "5" smd rect
			(at 1.905 -2.54)
			(size 0.635 1.651)
			(layers "F.Cu" "F.Mask" "F.Paste")
			(net "P12V_HDD27")
		)
		(pad "6" smd rect
			(at 0.635 -2.54)
			(size 0.635 1.651)
			(layers "F.Cu" "F.Mask" "F.Paste")
			(net "P12V_HDD27")
		)
		(pad "7" smd rect
			(at -0.635 -2.54)
			(size 0.635 1.651)
			(layers "F.Cu" "F.Mask" "F.Paste")
			(net "P12V_HDD27")
		)
		(pad "8" smd rect
			(at -1.905 -2.54)
			(size 0.635 1.651)
			(layers "F.Cu" "F.Mask" "F.Paste")
			(net "P12V_HDD27")
		)
	)
	(footprint ""
		(layer "F.Cu")
		(at 451.749922 -287.910016 -90)
		(property "Reference" "HDDSAS10"
			(at 0 0 270)
			(layer "F.SilkS")
			(hide yes)
			(effects
				(font
					(size 1.27 1.27)
				)
			)
		)
		(property "Value" "SKT-SAS15P-14P-45-GP"
			(at -20.7645 -8.9789 270)
			(unlocked yes)
			(layer "F.Fab")
			(hide yes)
			(effects
				(font
					(size 1.016 1.016)
					(thickness 0.1524)
				)
			)
		)
		(property "Device Type" "10120818-001C-TRLF"
			(at -20.7645 -10.5029 270)
			(unlocked yes)
			(layer "F.Fab")
			(hide yes)
			(effects
				(font
					(size 1.016 1.016)
					(thickness 0.1524)
				)
			)
		)
		(duplicate_pad_numbers_are_jumpers no)
		(fp_line
			(start 1.651 4.2926)
			(end 1.651 3.0099)
			(stroke
				(width 0.1524)
				(type default)
			)
			(layer "F.SilkS")
		)
		(fp_line
			(start 8.509 4.2926)
			(end 1.651 4.2926)
			(stroke
				(width 0.1524)
				(type default)
			)
			(layer "F.SilkS")
		)
		(fp_line
			(start -23.4188 3.0099)
			(end -23.4188 -3.2512)
			(stroke
				(width 0.1524)
				(type default)
			)
			(layer "F.SilkS")
		)
		(fp_line
			(start 1.651 3.0099)
			(end -23.4188 3.0099)
			(stroke
				(width 0.1524)
				(type default)
			)
			(layer "F.SilkS")
		)
		(fp_line
			(start 8.509 3.0099)
			(end 8.509 4.2926)
			(stroke
				(width 0.1524)
				(type default)
			)
			(layer "F.SilkS")
		)
		(fp_line
			(start 23.4188 3.0099)
			(end 8.509 3.0099)
			(stroke
				(width 0.1524)
				(type default)
			)
			(layer "F.SilkS")
		)
		(fp_line
			(start -23.4188 -3.2512)
			(end 23.4188 -3.2512)
			(stroke
				(width 0.1524)
				(type default)
			)
			(layer "F.SilkS")
		)
		(fp_line
			(start 23.4188 -3.2512)
			(end 23.4188 3.0099)
			(stroke
				(width 0.1524)
				(type default)
			)
			(layer "F.SilkS")
		)
		(fp_line
			(start 15.5067 -3.3401)
			(end 16.2687 -3.3401)
			(stroke
				(width 0.3302)
				(type default)
			)
			(layer "F.SilkS")
		)
		(fp_poly
			(pts
				(xy 15.868904 -3.230372) (xy 16.503904 -3.865372) (xy 15.233904 -3.865372)
			)
			(stroke
				(width 0)
				(type default)
			)
			(fill yes)
			(layer "F.SilkS")
		)
		(fp_poly
			(pts
				(xy -22.8727 -2.7559) (xy 22.8727 -2.7559) (xy 22.8727 2.7559) (xy 8.255 2.7559) (xy 8.255 3.5179)
				(xy 1.905 3.5179) (xy 1.905 2.7559) (xy -22.8727 2.7559)
			)
			(stroke
				(width 0)
				(type default)
			)
			(fill no)
			(layer "F.CrtYd")
		)
		(fp_poly
			(pts
				(xy 1.397 4.5466) (xy 1.397 3.2639) (xy -23.6728 3.2639) (xy -23.6728 -3.5052) (xy 23.6728 -3.5052)
				(xy 23.6728 -0.00635) (xy 22.8727 -0.00635) (xy 22.8727 -2.7559) (xy -22.8727 -2.7559) (xy -22.8727 2.7559)
				(xy 1.905 2.7559) (xy 1.905 3.5179) (xy 8.255 3.5179) (xy 8.255 2.7559) (xy 22.8727 2.7559) (xy 22.8727 0.00635)
				(xy 23.6728 0.00635) (xy 23.6728 3.2639) (xy 8.763 3.2639) (xy 8.763 4.5466)
			)
			(stroke
				(width 0)
				(type default)
			)
			(fill no)
			(layer "F.CrtYd")
		)
		(fp_poly
			(pts
				(xy 1.397 4.5466) (xy 1.397 3.2639) (xy -23.6728 3.2639) (xy -23.6728 -3.5052) (xy 23.6728 -3.5052)
				(xy 23.6728 3.2639) (xy 8.763 3.2639) (xy 8.763 4.5466)
			)
			(stroke
				(width 0)
				(type default)
			)
			(fill no)
			(layer "F.Fab")
		)
		(pad "" np_thru_hole circle
			(at -18.874994 0 270)
			(size 0.254 0.254)
			(drill 1.3462)
			(layers "*.Cu" "*.Mask")
			(clearance 0.9017)
			(thermal_gap 0.9017)
		)
		(pad "" np_thru_hole circle
			(at 18.874994 0 270)
			(size 0.254 0.254)
			(drill 0.9398)
			(layers "*.Cu" "*.Mask")
			(clearance 0.6985)
			(thermal_gap 0.6985)
		)
		(pad "G1" smd rect
			(at 21.874988 0 270)
			(size 2.5908 2.5908)
			(layers "F.Cu" "F.Mask" "F.Paste")
			(net "GND")
		)
		(pad "G2" smd rect
			(at -21.874988 0 270)
			(size 2.5908 2.5908)
			(layers "F.Cu" "F.Mask" "F.Paste")
			(net "GND")
		)
		(pad "P1" smd rect
			(at 1.905 -1.82499 270)
			(size 0.6096 2.3622)
			(layers "F.Cu" "F.Mask" "F.Paste")
			(net "Net_2166")
		)
		(pad "P2" smd rect
			(at 0.635 -1.82499 270)
			(size 0.6096 2.3622)
			(layers "F.Cu" "F.Mask" "F.Paste")
			(net "Net_2167")
		)
		(pad "P3" smd rect
			(at -0.635 -1.82499 270)
			(size 0.6096 2.3622)
			(layers "F.Cu" "F.Mask" "F.Paste")
			(net "Net_2168")
		)
		(pad "P4" smd rect
			(at -1.905 -1.82499 270)
			(size 0.6096 2.3622)
			(layers "F.Cu" "F.Mask" "F.Paste")
			(net "GND")
		)
		(pad "P5" smd rect
			(at -3.175 -1.82499 270)
			(size 0.6096 2.3622)
			(layers "F.Cu" "F.Mask" "F.Paste")
			(net "HDD_PRSNT_10")
		)
		(pad "P6" smd rect
			(at -4.445 -1.82499 270)
			(size 0.6096 2.3622)
			(layers "F.Cu" "F.Mask" "F.Paste")
			(net "GND")
		)
		(pad "P7" smd rect
			(at -5.715 -1.82499 270)
			(size 0.6096 2.3622)
			(layers "F.Cu" "F.Mask" "F.Paste")
			(net "5V_PRE_10")
		)
		(pad "P8" smd rect
			(at -6.985 -1.82499 270)
			(size 0.6096 2.3622)
			(layers "F.Cu" "F.Mask" "F.Paste")
			(net "P5V_HDD10")
		)
		(pad "P9" smd rect
			(at -8.255 -1.82499 270)
			(size 0.6096 2.3622)
			(layers "F.Cu" "F.Mask" "F.Paste")
			(net "P5V_HDD10")
		)
		(pad "P10" smd rect
			(at -9.525 -1.82499 270)
			(size 0.6096 2.3622)
			(layers "F.Cu" "F.Mask" "F.Paste")
			(net "GND")
		)
		(pad "P11" smd rect
			(at -10.795 -1.82499 270)
			(size 0.6096 2.3622)
			(layers "F.Cu" "F.Mask" "F.Paste")
			(net "ACT_HDD_10")
		)
		(pad "P12" smd rect
			(at -12.065 -1.82499 270)
			(size 0.6096 2.3622)
			(layers "F.Cu" "F.Mask" "F.Paste")
			(net "GND")
		)
		(pad "P13" smd rect
			(at -13.335 -1.82499 270)
			(size 0.6096 2.3622)
			(layers "F.Cu" "F.Mask" "F.Paste")
			(net "12V_PRE_10")
		)
		(pad "P14" smd rect
			(at -14.605 -1.82499 270)
			(size 0.6096 2.3622)
			(layers "F.Cu" "F.Mask" "F.Paste")
			(net "P12V_HDD10")
		)
		(pad "P15" smd rect
			(at -15.875 -1.82499 270)
			(size 0.6096 2.3622)
			(layers "F.Cu" "F.Mask" "F.Paste")
			(net "P12V_HDD10")
		)
		(pad "S1" smd rect
			(at 15.875 -1.82499 270)
			(size 0.6096 2.3622)
			(layers "F.Cu" "F.Mask" "F.Paste")
			(net "GND")
		)
		(pad "S2" smd rect
			(at 14.605 -1.82499 270)
			(size 0.6096 2.3622)
			(layers "F.Cu" "F.Mask" "F.Paste")
			(net "SAS_HDD_RX_P10")
		)
		(pad "S3" smd rect
			(at 13.335 -1.82499 270)
			(size 0.6096 2.3622)
			(layers "F.Cu" "F.Mask" "F.Paste")
			(net "SAS_HDD_RX_N10")
		)
		(pad "S4" smd rect
			(at 12.065 -1.82499 270)
			(size 0.6096 2.3622)
			(layers "F.Cu" "F.Mask" "F.Paste")
			(net "GND")
		)
		(pad "S5" smd rect
			(at 10.795 -1.82499 270)
			(size 0.6096 2.3622)
			(layers "F.Cu" "F.Mask" "F.Paste")
			(net "PHY_DRV_A_TO_SCC_A_10_DN")
		)
		(pad "S6" smd rect
			(at 9.525 -1.82499 270)
			(size 0.6096 2.3622)
			(layers "F.Cu" "F.Mask" "F.Paste")
			(net "PHY_DRV_A_TO_SCC_A_10_DP")
		)
		(pad "S7" smd rect
			(at 8.255 -1.82499 270)
			(size 0.6096 2.3622)
			(layers "F.Cu" "F.Mask" "F.Paste")
			(net "GND")
		)
		(pad "S8" smd rect
			(at 7.480046 2.845054 270)
			(size 0.508 2.3622)
			(layers "F.Cu" "F.Mask" "F.Paste")
			(net "GND")
		)
		(pad "S9" smd rect
			(at 6.679946 2.845054 270)
			(size 0.508 2.3622)
			(layers "F.Cu" "F.Mask" "F.Paste")
			(net "Net_447")
		)
		(pad "S10" smd rect
			(at 5.8801 2.845054 270)
			(size 0.508 2.3622)
			(layers "F.Cu" "F.Mask" "F.Paste")
			(net "Net_339")
		)
		(pad "S11" smd rect
			(at 5.08 2.845054 270)
			(size 0.508 2.3622)
			(layers "F.Cu" "F.Mask" "F.Paste")
			(net "GND")
		)
		(pad "S12" smd rect
			(at 4.2799 2.845054 270)
			(size 0.508 2.3622)
			(layers "F.Cu" "F.Mask" "F.Paste")
			(net "Net_375")
		)
		(pad "S13" smd rect
			(at 3.480054 2.845054 270)
			(size 0.508 2.3622)
			(layers "F.Cu" "F.Mask" "F.Paste")
			(net "Net_411")
		)
		(pad "S14" smd rect
			(at 2.679954 2.845054 270)
			(size 0.508 2.3622)
			(layers "F.Cu" "F.Mask" "F.Paste")
			(net "GND")
		)
		(zone
			(layer "F.Cu")
			(hatch none 0.5)
			(connect_pads
				(clearance 0)
			)
			(min_thickness 0.25)
			(keepout
				(tracks allowed)
				(vias not_allowed)
				(pads allowed)
				(copperpour not_allowed)
				(footprints allowed)
			)
			(placement
				(enabled no)
				(sheetname "")
			)
			(fill
				(thermal_gap 0.5)
				(thermal_bridge_width 0.5)
				(island_removal_mode 0)
			)
			(polygon
				(pts
					(xy 455.407522 -304.648616) (xy 448.333622 -304.648616) (xy 448.333622 -311.582816) (xy 449.438522 -311.582816)
					(xy 449.438522 -307.468016) (xy 454.061322 -307.468016) (xy 454.061322 -311.582816) (xy 455.407522 -311.582816)
				)
			)
		)
		(zone
			(layer "F.Cu")
			(hatch none 0.5)
			(connect_pads
				(clearance 0)
			)
			(min_thickness 0.25)
			(keepout
				(tracks not_allowed)
				(vias allowed)
				(pads allowed)
				(copperpour not_allowed)
				(footprints allowed)
			)
			(placement
				(enabled no)
				(sheetname "")
			)
			(fill
				(thermal_gap 0.5)
				(thermal_bridge_width 0.5)
				(island_removal_mode 0)
			)
			(polygon
				(pts
					(xy 455.407522 -304.648616) (xy 448.333622 -304.648616) (xy 448.333622 -311.582816) (xy 449.438522 -311.582816)
					(xy 449.438522 -307.468016) (xy 454.061322 -307.468016) (xy 454.061322 -311.582816) (xy 455.407522 -311.582816)
				)
			)
		)
		(zone
			(layer "F.Cu")
			(hatch none 0.5)
			(connect_pads
				(clearance 0)
			)
			(min_thickness 0.25)
			(keepout
				(tracks not_allowed)
				(vias allowed)
				(pads allowed)
				(copperpour not_allowed)
				(footprints allowed)
			)
			(placement
				(enabled no)
				(sheetname "")
			)
			(fill
				(thermal_gap 0.5)
				(thermal_bridge_width 0.5)
				(island_removal_mode 0)
			)
			(polygon
				(pts
					(xy 455.407522 -271.171416) (xy 448.333622 -271.171416) (xy 448.333622 -264.237216) (xy 449.438522 -264.237216)
					(xy 449.438522 -268.352016) (xy 454.061322 -268.352016) (xy 454.061322 -264.237216) (xy 455.407522 -264.237216)
				)
			)
		)
		(zone
			(layer "F.Cu")
			(hatch none 0.5)
			(connect_pads
				(clearance 0)
			)
			(min_thickness 0.25)
			(keepout
				(tracks allowed)
				(vias not_allowed)
				(pads allowed)
				(copperpour not_allowed)
				(footprints allowed)
			)
			(placement
				(enabled no)
				(sheetname "")
			)
			(fill
				(thermal_gap 0.5)
				(thermal_bridge_width 0.5)
				(island_removal_mode 0)
			)
			(polygon
				(pts
					(xy 455.407522 -271.171416) (xy 448.333622 -271.171416) (xy 448.333622 -264.237216) (xy 449.438522 -264.237216)
					(xy 449.438522 -268.352016) (xy 454.061322 -268.352016) (xy 454.061322 -264.237216) (xy 455.407522 -264.237216)
				)
			)
		)
		(zone
			(layers "F.Cu" "B.Cu" "In1.Cu" "In2.Cu" "In3.Cu" "In4.Cu" "In5.Cu" "In6.Cu"
				"In7.Cu" "In8.Cu" "In9.Cu" "In10.Cu"
			)
			(hatch none 0.5)
			(connect_pads
				(clearance 0)
			)
			(min_thickness 0.25)
			(keepout
				(tracks not_allowed)
				(vias allowed)
				(pads allowed)
				(copperpour not_allowed)
				(footprints allowed)
			)
			(placement
				(enabled no)
				(sheetname "")
			)
			(fill
				(thermal_gap 0.5)
				(thermal_bridge_width 0.5)
				(island_removal_mode 0)
			)
			(polygon
				(pts
					(arc
						(start 452.524622 -269.035022)
						(mid 450.975222 -269.035022)
						(end 452.524622 -269.035022)
					)
				)
			)
		)
		(zone
			(layers "F.Cu" "B.Cu" "In1.Cu" "In2.Cu" "In3.Cu" "In4.Cu" "In5.Cu" "In6.Cu"
				"In7.Cu" "In8.Cu" "In9.Cu" "In10.Cu"
			)
			(hatch none 0.5)
			(connect_pads
				(clearance 0)
			)
			(min_thickness 0.25)
			(keepout
				(tracks not_allowed)
				(vias allowed)
				(pads allowed)
				(copperpour not_allowed)
				(footprints allowed)
			)
			(placement
				(enabled no)
				(sheetname "")
			)
			(fill
				(thermal_gap 0.5)
				(thermal_bridge_width 0.5)
				(island_removal_mode 0)
			)
			(polygon
				(pts
					(arc
						(start 452.727822 -306.78501)
						(mid 450.772022 -306.78501)
						(end 452.727822 -306.78501)
					)
				)
			)
		)
	)
)
